(kicad_pcb
	(version 20260206)
	(generator "pcbnew")
	(generator_version "10.0")
	(general
		(thickness 1.6)
		(legacy_teardrops no)
	)
	(paper "A4")
	(title_block
		(title "03242023_DA0F0TMBIJ0_F0T_Motherboard_J_brd_V01_OCP.brd")
		(comment 1 "Grand Teton / footprints 379-383 of 6105")
	)
	(layers
		(0 "F.Cu" signal "TOP")
		(4 "In1.Cu" signal "GND")
		(6 "In2.Cu" signal "IN1")
		(8 "In3.Cu" signal "GND1")
		(10 "In4.Cu" signal "IN2")
		(12 "In5.Cu" signal "GND2")
		(14 "In6.Cu" signal "IN3")
		(16 "In7.Cu" signal "GND3")
		(18 "In8.Cu" signal "VCC")
		(20 "In9.Cu" signal "VCC1")
		(22 "In10.Cu" signal "GND4")
		(24 "In11.Cu" signal "IN4")
		(26 "In12.Cu" signal "GND5")
		(28 "In13.Cu" signal "IN5")
		(30 "In14.Cu" signal "GND6")
		(32 "In15.Cu" signal "IN6")
		(34 "In16.Cu" signal "GND7")
		(2 "B.Cu" signal "BOTTOM")
		(9 "F.Adhes" user "F.Adhesive")
		(11 "B.Adhes" user "B.Adhesive")
		(13 "F.Paste" user "Package Geometry/Pastemask Top")
		(15 "B.Paste" user "Package Geometry/Pastemask Bottom")
		(5 "F.SilkS" user "Ref Des/Silkscreen Top")
		(7 "B.SilkS" user "Ref Des/Silkscreen Bottom")
		(1 "F.Mask" user "Board Geometry/Soldermask Top")
		(3 "B.Mask" user "Board Geometry/Soldermask Bottom")
		(17 "Dwgs.User" user "User.Drawings")
		(19 "Cmts.User" user "User.Comments")
		(21 "Eco1.User" user "User.Eco1")
		(23 "Eco2.User" user "User.Eco2")
		(25 "Edge.Cuts" user "Board Geometry/Outline")
		(27 "Margin" user)
		(31 "F.CrtYd" user "Package Geometry/Place Bound Top")
		(29 "B.CrtYd" user "Package Geometry/Place Bound Bottom")
		(35 "F.Fab" user "Ref Des/Assembly Top")
		(33 "B.Fab" user "Ref Des/Assembly Bottom")
	)
	(footprint ""
		(layer "F.Cu")
		(at 51.10988 -170.576748 -90)
		(property "Reference" "PR1799"
			(at 0 0 270)
			(layer "F.SilkS")
			(hide yes)
			(effects
				(font
					(size 1.27 1.27)
				)
			)
		)
		(property "Value" ""
			(at 0 0 270)
			(layer "F.Fab")
			(effects
				(font
					(size 1.27 1.27)
				)
			)
		)
		(duplicate_pad_numbers_are_jumpers no)
		(fp_line
			(start -0.7874 0.4064)
			(end -0.7874 -0.4064)
			(stroke
				(width 0.1524)
				(type default)
			)
			(layer "F.SilkS")
		)
		(fp_line
			(start 0.7874 0.4064)
			(end -0.7874 0.4064)
			(stroke
				(width 0.1524)
				(type default)
			)
			(layer "F.SilkS")
		)
		(fp_line
			(start -0.7874 -0.4064)
			(end 0.7874 -0.4064)
			(stroke
				(width 0.1524)
				(type default)
			)
			(layer "F.SilkS")
		)
		(fp_line
			(start 0.7874 -0.4064)
			(end 0.7874 0.4064)
			(stroke
				(width 0.1524)
				(type default)
			)
			(layer "F.SilkS")
		)
		(fp_line
			(start -0.67945 0.3048)
			(end -0.67945 -0.305054)
			(stroke
				(width 0.1)
				(type default)
			)
			(layer "F.Fab")
		)
		(fp_line
			(start -0.12065 0.3048)
			(end -0.67945 0.3048)
			(stroke
				(width 0.1)
				(type default)
			)
			(layer "F.Fab")
		)
		(fp_line
			(start 0.120396 0.3048)
			(end 0.120396 0.2794)
			(stroke
				(width 0.1)
				(type default)
			)
			(layer "F.Fab")
		)
		(fp_line
			(start 0.67945 0.3048)
			(end 0.120396 0.3048)
			(stroke
				(width 0.1)
				(type default)
			)
			(layer "F.Fab")
		)
		(fp_line
			(start -0.12065 0.2794)
			(end -0.12065 0.3048)
			(stroke
				(width 0.1)
				(type default)
			)
			(layer "F.Fab")
		)
		(fp_line
			(start 0.120396 0.2794)
			(end -0.12065 0.2794)
			(stroke
				(width 0.1)
				(type default)
			)
			(layer "F.Fab")
		)
		(fp_line
			(start -0.12065 -0.2794)
			(end 0.12065 -0.2794)
			(stroke
				(width 0.1)
				(type default)
			)
			(layer "F.Fab")
		)
		(fp_line
			(start 0.12065 -0.2794)
			(end 0.12065 -0.3048)
			(stroke
				(width 0.1)
				(type default)
			)
			(layer "F.Fab")
		)
		(fp_line
			(start 0.12065 -0.3048)
			(end 0.67945 -0.3048)
			(stroke
				(width 0.1)
				(type default)
			)
			(layer "F.Fab")
		)
		(fp_line
			(start 0.67945 -0.3048)
			(end 0.67945 0.3048)
			(stroke
				(width 0.1)
				(type default)
			)
			(layer "F.Fab")
		)
		(fp_line
			(start -0.67945 -0.305054)
			(end -0.12065 -0.305054)
			(stroke
				(width 0.1)
				(type default)
			)
			(layer "F.Fab")
		)
		(fp_line
			(start -0.12065 -0.305054)
			(end -0.12065 -0.2794)
			(stroke
				(width 0.1)
				(type default)
			)
			(layer "F.Fab")
		)
		(pad "1" smd circle
			(at -0.40005 0 270)
			(size 0 0)
			(layers "F.Cu" "F.Mask" "F.Paste")
			(net "PVCCFA_EHV_CPU1_NC1")
		)
		(pad "2" smd circle
			(at 0.40005 0 270)
			(size 0 0)
			(layers "F.Cu" "F.Mask" "F.Paste")
			(net "PVCCFA_EHV_CPU1_VDD1")
		)
	)
	(footprint ""
		(layer "F.Cu")
		(at 448.980052 -18.063464 -90)
		(property "Reference" "PR3787"
			(at 0 0 270)
			(layer "F.SilkS")
			(hide yes)
			(effects
				(font
					(size 1.27 1.27)
				)
			)
		)
		(property "Value" ""
			(at 0 0 270)
			(layer "F.Fab")
			(effects
				(font
					(size 1.27 1.27)
				)
			)
		)
		(duplicate_pad_numbers_are_jumpers no)
		(fp_line
			(start -0.7874 0.4064)
			(end -0.7874 -0.4064)
			(stroke
				(width 0.1524)
				(type default)
			)
			(layer "F.SilkS")
		)
		(fp_line
			(start 0.7874 0.4064)
			(end -0.7874 0.4064)
			(stroke
				(width 0.1524)
				(type default)
			)
			(layer "F.SilkS")
		)
		(fp_line
			(start -0.7874 -0.4064)
			(end 0.7874 -0.4064)
			(stroke
				(width 0.1524)
				(type default)
			)
			(layer "F.SilkS")
		)
		(fp_line
			(start 0.7874 -0.4064)
			(end 0.7874 0.4064)
			(stroke
				(width 0.1524)
				(type default)
			)
			(layer "F.SilkS")
		)
		(fp_line
			(start -0.67945 0.3048)
			(end -0.67945 -0.305054)
			(stroke
				(width 0.1)
				(type default)
			)
			(layer "F.Fab")
		)
		(fp_line
			(start -0.12065 0.3048)
			(end -0.67945 0.3048)
			(stroke
				(width 0.1)
				(type default)
			)
			(layer "F.Fab")
		)
		(fp_line
			(start 0.120396 0.3048)
			(end 0.120396 0.2794)
			(stroke
				(width 0.1)
				(type default)
			)
			(layer "F.Fab")
		)
		(fp_line
			(start 0.67945 0.3048)
			(end 0.120396 0.3048)
			(stroke
				(width 0.1)
				(type default)
			)
			(layer "F.Fab")
		)
		(fp_line
			(start -0.12065 0.2794)
			(end -0.12065 0.3048)
			(stroke
				(width 0.1)
				(type default)
			)
			(layer "F.Fab")
		)
		(fp_line
			(start 0.120396 0.2794)
			(end -0.12065 0.2794)
			(stroke
				(width 0.1)
				(type default)
			)
			(layer "F.Fab")
		)
		(fp_line
			(start -0.12065 -0.2794)
			(end 0.12065 -0.2794)
			(stroke
				(width 0.1)
				(type default)
			)
			(layer "F.Fab")
		)
		(fp_line
			(start 0.12065 -0.2794)
			(end 0.12065 -0.3048)
			(stroke
				(width 0.1)
				(type default)
			)
			(layer "F.Fab")
		)
		(fp_line
			(start 0.12065 -0.3048)
			(end 0.67945 -0.3048)
			(stroke
				(width 0.1)
				(type default)
			)
			(layer "F.Fab")
		)
		(fp_line
			(start 0.67945 -0.3048)
			(end 0.67945 0.3048)
			(stroke
				(width 0.1)
				(type default)
			)
			(layer "F.Fab")
		)
		(fp_line
			(start -0.67945 -0.305054)
			(end -0.12065 -0.305054)
			(stroke
				(width 0.1)
				(type default)
			)
			(layer "F.Fab")
		)
		(fp_line
			(start -0.12065 -0.305054)
			(end -0.12065 -0.2794)
			(stroke
				(width 0.1)
				(type default)
			)
			(layer "F.Fab")
		)
		(pad "1" smd circle
			(at -0.40005 0 270)
			(size 0 0)
			(layers "F.Cu" "F.Mask" "F.Paste")
			(net "P12V_OCP_UV_1")
		)
		(pad "2" smd circle
			(at 0.40005 0 270)
			(size 0 0)
			(layers "F.Cu" "F.Mask" "F.Paste")
			(net "P12V_OCP_OV_1")
		)
	)
	(footprint ""
		(layer "F.Cu")
		(at 22.809454 -108.793026 180)
		(property "Reference" "R3689"
			(at 0 0 180)
			(layer "F.SilkS")
			(hide yes)
			(effects
				(font
					(size 1.27 1.27)
				)
			)
		)
		(property "Value" ""
			(at 0 0 180)
			(layer "F.Fab")
			(effects
				(font
					(size 1.27 1.27)
				)
			)
		)
		(duplicate_pad_numbers_are_jumpers no)
		(fp_line
			(start 0.7874 0.4064)
			(end -0.7874 0.4064)
			(stroke
				(width 0.1524)
				(type default)
			)
			(layer "F.SilkS")
		)
		(fp_line
			(start 0.7874 -0.4064)
			(end 0.7874 0.4064)
			(stroke
				(width 0.1524)
				(type default)
			)
			(layer "F.SilkS")
		)
		(fp_line
			(start -0.7874 0.4064)
			(end -0.7874 -0.4064)
			(stroke
				(width 0.1524)
				(type default)
			)
			(layer "F.SilkS")
		)
		(fp_line
			(start -0.7874 -0.4064)
			(end 0.7874 -0.4064)
			(stroke
				(width 0.1524)
				(type default)
			)
			(layer "F.SilkS")
		)
		(fp_line
			(start 0.67945 0.3048)
			(end 0.120396 0.3048)
			(stroke
				(width 0.1)
				(type default)
			)
			(layer "F.Fab")
		)
		(fp_line
			(start 0.67945 -0.3048)
			(end 0.67945 0.3048)
			(stroke
				(width 0.1)
				(type default)
			)
			(layer "F.Fab")
		)
		(fp_line
			(start 0.12065 -0.2794)
			(end 0.12065 -0.3048)
			(stroke
				(width 0.1)
				(type default)
			)
			(layer "F.Fab")
		)
		(fp_line
			(start 0.12065 -0.3048)
			(end 0.67945 -0.3048)
			(stroke
				(width 0.1)
				(type default)
			)
			(layer "F.Fab")
		)
		(fp_line
			(start 0.120396 0.3048)
			(end 0.120396 0.2794)
			(stroke
				(width 0.1)
				(type default)
			)
			(layer "F.Fab")
		)
		(fp_line
			(start 0.120396 0.2794)
			(end -0.12065 0.2794)
			(stroke
				(width 0.1)
				(type default)
			)
			(layer "F.Fab")
		)
		(fp_line
			(start -0.12065 0.3048)
			(end -0.67945 0.3048)
			(stroke
				(width 0.1)
				(type default)
			)
			(layer "F.Fab")
		)
		(fp_line
			(start -0.12065 0.2794)
			(end -0.12065 0.3048)
			(stroke
				(width 0.1)
				(type default)
			)
			(layer "F.Fab")
		)
		(fp_line
			(start -0.12065 -0.2794)
			(end 0.12065 -0.2794)
			(stroke
				(width 0.1)
				(type default)
			)
			(layer "F.Fab")
		)
		(fp_line
			(start -0.12065 -0.305054)
			(end -0.12065 -0.2794)
			(stroke
				(width 0.1)
				(type default)
			)
			(layer "F.Fab")
		)
		(fp_line
			(start -0.67945 0.3048)
			(end -0.67945 -0.305054)
			(stroke
				(width 0.1)
				(type default)
			)
			(layer "F.Fab")
		)
		(fp_line
			(start -0.67945 -0.305054)
			(end -0.12065 -0.305054)
			(stroke
				(width 0.1)
				(type default)
			)
			(layer "F.Fab")
		)
		(pad "1" smd circle
			(at -0.40005 0 180)
			(size 0 0)
			(layers "F.Cu" "F.Mask" "F.Paste")
			(net "P3V3_ADC128_VCC")
		)
		(pad "2" smd circle
			(at 0.40005 0 180)
			(size 0 0)
			(layers "F.Cu" "F.Mask" "F.Paste")
			(net "ADC128_VREF")
		)
	)
	(footprint ""
		(layer "F.Cu")
		(at 51.593496 -105.34777)
		(property "Reference" "R3729"
			(at 0 0 0)
			(layer "F.SilkS")
			(hide yes)
			(effects
				(font
					(size 1.27 1.27)
				)
			)
		)
		(property "Value" ""
			(at 0 0 0)
			(layer "F.Fab")
			(effects
				(font
					(size 1.27 1.27)
				)
			)
		)
		(duplicate_pad_numbers_are_jumpers no)
		(fp_line
			(start -0.7874 -0.4064)
			(end 0.7874 -0.4064)
			(stroke
				(width 0.1524)
				(type default)
			)
			(layer "F.SilkS")
		)
		(fp_line
			(start -0.7874 0.4064)
			(end -0.7874 -0.4064)
			(stroke
				(width 0.1524)
				(type default)
			)
			(layer "F.SilkS")
		)
		(fp_line
			(start 0.7874 -0.4064)
			(end 0.7874 0.4064)
			(stroke
				(width 0.1524)
				(type default)
			)
			(layer "F.SilkS")
		)
		(fp_line
			(start 0.7874 0.4064)
			(end -0.7874 0.4064)
			(stroke
				(width 0.1524)
				(type default)
			)
			(layer "F.SilkS")
		)
		(fp_line
			(start -0.67945 -0.305054)
			(end -0.12065 -0.305054)
			(stroke
				(width 0.1)
				(type default)
			)
			(layer "F.Fab")
		)
		(fp_line
			(start -0.67945 0.3048)
			(end -0.67945 -0.305054)
			(stroke
				(width 0.1)
				(type default)
			)
			(layer "F.Fab")
		)
		(fp_line
			(start -0.12065 -0.305054)
			(end -0.12065 -0.2794)
			(stroke
				(width 0.1)
				(type default)
			)
			(layer "F.Fab")
		)
		(fp_line
			(start -0.12065 -0.2794)
			(end 0.12065 -0.2794)
			(stroke
				(width 0.1)
				(type default)
			)
			(layer "F.Fab")
		)
		(fp_line
			(start -0.12065 0.2794)
			(end -0.12065 0.3048)
			(stroke
				(width 0.1)
				(type default)
			)
			(layer "F.Fab")
		)
		(fp_line
			(start -0.12065 0.3048)
			(end -0.67945 0.3048)
			(stroke
				(width 0.1)
				(type default)
			)
			(layer "F.Fab")
		)
		(fp_line
			(start 0.120396 0.2794)
			(end -0.12065 0.2794)
			(stroke
				(width 0.1)
				(type default)
			)
			(layer "F.Fab")
		)
		(fp_line
			(start 0.120396 0.3048)
			(end 0.120396 0.2794)
			(stroke
				(width 0.1)
				(type default)
			)
			(layer "F.Fab")
		)
		(fp_line
			(start 0.12065 -0.3048)
			(end 0.67945 -0.3048)
			(stroke
				(width 0.1)
				(type default)
			)
			(layer "F.Fab")
		)
		(fp_line
			(start 0.12065 -0.2794)
			(end 0.12065 -0.3048)
			(stroke
				(width 0.1)
				(type default)
			)
			(layer "F.Fab")
		)
		(fp_line
			(start 0.67945 -0.3048)
			(end 0.67945 0.3048)
			(stroke
				(width 0.1)
				(type default)
			)
			(layer "F.Fab")
		)
		(fp_line
			(start 0.67945 0.3048)
			(end 0.120396 0.3048)
			(stroke
				(width 0.1)
				(type default)
			)
			(layer "F.Fab")
		)
		(pad "1" smd circle
			(at -0.40005 0)
			(size 0 0)
			(layers "F.Cu" "F.Mask" "F.Paste")
			(net "P3V3_AUX")
		)
		(pad "2" smd circle
			(at 0.40005 0)
			(size 0 0)
			(layers "F.Cu" "F.Mask" "F.Paste")
			(net "SMB_LM75_2_3V3AUX_SCL")
		)
	)
	(footprint ""
		(layer "F.Cu")
		(at 193.90868 -358.206548)
		(property "Reference" "R628"
			(at 0 0 0)
			(layer "F.SilkS")
			(hide yes)
			(effects
				(font
					(size 1.27 1.27)
				)
			)
		)
		(property "Value" ""
			(at 0 0 0)
			(layer "F.Fab")
			(effects
				(font
					(size 1.27 1.27)
				)
			)
		)
		(duplicate_pad_numbers_are_jumpers no)
		(fp_line
			(start -0.7874 -0.4064)
			(end 0.7874 -0.4064)
			(stroke
				(width 0.1524)
				(type default)
			)
			(layer "F.SilkS")
		)
		(fp_line
			(start -0.7874 0.4064)
			(end -0.7874 -0.4064)
			(stroke
				(width 0.1524)
				(type default)
			)
			(layer "F.SilkS")
		)
		(fp_line
			(start 0.7874 -0.4064)
			(end 0.7874 0.4064)
			(stroke
				(width 0.1524)
				(type default)
			)
			(layer "F.SilkS")
		)
		(fp_line
			(start 0.7874 0.4064)
			(end -0.7874 0.4064)
			(stroke
				(width 0.1524)
				(type default)
			)
			(layer "F.SilkS")
		)
		(fp_line
			(start -0.67945 -0.305054)
			(end -0.12065 -0.305054)
			(stroke
				(width 0.1)
				(type default)
			)
			(layer "F.Fab")
		)
		(fp_line
			(start -0.67945 0.3048)
			(end -0.67945 -0.305054)
			(stroke
				(width 0.1)
				(type default)
			)
			(layer "F.Fab")
		)
		(fp_line
			(start -0.12065 -0.305054)
			(end -0.12065 -0.2794)
			(stroke
				(width 0.1)
				(type default)
			)
			(layer "F.Fab")
		)
		(fp_line
			(start -0.12065 -0.2794)
			(end 0.12065 -0.2794)
			(stroke
				(width 0.1)
				(type default)
			)
			(layer "F.Fab")
		)
		(fp_line
			(start -0.12065 0.2794)
			(end -0.12065 0.3048)
			(stroke
				(width 0.1)
				(type default)
			)
			(layer "F.Fab")
		)
		(fp_line
			(start -0.12065 0.3048)
			(end -0.67945 0.3048)
			(stroke
				(width 0.1)
				(type default)
			)
			(layer "F.Fab")
		)
		(fp_line
			(start 0.120396 0.2794)
			(end -0.12065 0.2794)
			(stroke
				(width 0.1)
				(type default)
			)
			(layer "F.Fab")
		)
		(fp_line
			(start 0.120396 0.3048)
			(end 0.120396 0.2794)
			(stroke
				(width 0.1)
				(type default)
			)
			(layer "F.Fab")
		)
		(fp_line
			(start 0.12065 -0.3048)
			(end 0.67945 -0.3048)
			(stroke
				(width 0.1)
				(type default)
			)
			(layer "F.Fab")
		)
		(fp_line
			(start 0.12065 -0.2794)
			(end 0.12065 -0.3048)
			(stroke
				(width 0.1)
				(type default)
			)
			(layer "F.Fab")
		)
		(fp_line
			(start 0.67945 -0.3048)
			(end 0.67945 0.3048)
			(stroke
				(width 0.1)
				(type default)
			)
			(layer "F.Fab")
		)
		(fp_line
			(start 0.67945 0.3048)
			(end 0.120396 0.3048)
			(stroke
				(width 0.1)
				(type default)
			)
			(layer "F.Fab")
		)
		(pad "1" smd circle
			(at -0.40005 0)
			(size 0 0)
			(layers "F.Cu" "F.Mask" "F.Paste")
			(net "PD_PIROM_CPU1_ADDR1")
		)
		(pad "2" smd circle
			(at 0.40005 0)
			(size 0 0)
			(layers "F.Cu" "F.Mask" "F.Paste")
			(net "GND")
		)
	)
)
